# S9S_MB_2U (Grand Teton) — schematic netlist excerpt (pin names and nets, part order shuffled) for the footprints in the layout excerpt that follows; sources: Cadence DE-HDL packaged netlist, KiCad conversion of 03242023_DA0F0TMBIJ0_F0T_Motherboard_J_brd_V01_OCP.brd

J121  PICOPROBE_BXA  DELTA-L 4.0 EMPTY  pkg TRIANG_LAUNCH_3PXB  page 308
  \1_p\  = DELTA_L_85_10INCH_IN6_DN
  \2_n\  = DELTA_L_85_10INCH_IN6_DP
  \3_g\  = DELTA_L_GND_1

(kicad_pcb
	(version 20260206)
	(generator "pcbnew")
	(generator_version "10.0")
	(general
		(thickness 1.6)
		(legacy_teardrops no)
	)
	(paper "A4")
	(title_block
		(title "03242023_DA0F0TMBIJ0_F0T_Motherboard_J_brd_V01_OCP.brd")
		(comment 1 "Grand Teton / footprints 4466-4466 of 6105")
	)
	(layers
		(0 "F.Cu" signal "TOP")
		(4 "In1.Cu" signal "GND")
		(6 "In2.Cu" signal "IN1")
		(8 "In3.Cu" signal "GND1")
		(10 "In4.Cu" signal "IN2")
		(12 "In5.Cu" signal "GND2")
		(14 "In6.Cu" signal "IN3")
		(16 "In7.Cu" signal "GND3")
		(18 "In8.Cu" signal "VCC")
		(20 "In9.Cu" signal "VCC1")
		(22 "In10.Cu" signal "GND4")
		(24 "In11.Cu" signal "IN4")
		(26 "In12.Cu" signal "GND5")
		(28 "In13.Cu" signal "IN5")
		(30 "In14.Cu" signal "GND6")
		(32 "In15.Cu" signal "IN6")
		(34 "In16.Cu" signal "GND7")
		(2 "B.Cu" signal "BOTTOM")
		(9 "F.Adhes" user "F.Adhesive")
		(11 "B.Adhes" user "B.Adhesive")
		(13 "F.Paste" user "Package Geometry/Pastemask Top")
		(15 "B.Paste" user "Package Geometry/Pastemask Bottom")
		(5 "F.SilkS" user "Ref Des/Silkscreen Top")
		(7 "B.SilkS" user "Ref Des/Silkscreen Bottom")
		(1 "F.Mask" user "Board Geometry/Soldermask Top")
		(3 "B.Mask" user "Board Geometry/Soldermask Bottom")
		(17 "Dwgs.User" user "User.Drawings")
		(19 "Cmts.User" user "User.Comments")
		(21 "Eco1.User" user "User.Eco1")
		(23 "Eco2.User" user "User.Eco2")
		(25 "Edge.Cuts" user "Board Geometry/Outline")
		(27 "Margin" user)
		(31 "F.CrtYd" user "Package Geometry/Place Bound Top")
		(29 "B.CrtYd" user "Package Geometry/Place Bound Bottom")
		(35 "F.Fab" user "Ref Des/Assembly Top")
		(33 "B.Fab" user "Ref Des/Assembly Bottom")
	)
	(footprint ""
		(layer "B.Cu")
		(at 260.731508 2.923794 180)
		(property "Reference" "J121"
			(at 4.218178 -1.394206 270)
			(unlocked yes)
			(layer "B.SilkS")
			(effects
				(font
					(size 0.7874 0.5842)
					(thickness 0.1524)
				)
				(justify left mirror)
			)
		)
		(property "Value" ""
			(at 0 0 0)
			(layer "B.Fab")
			(effects
				(font
					(size 1.27 1.27)
				)
				(justify mirror)
			)
		)
		(duplicate_pad_numbers_are_jumpers no)
		(fp_line
			(start 1.2192 2.1082)
			(end 1.2192 -2.1082)
			(stroke
				(width 0.1524)
				(type default)
			)
			(layer "B.SilkS")
		)
		(fp_line
			(start 1.2192 -2.1082)
			(end -1.2192 -2.1082)
			(stroke
				(width 0.1524)
				(type default)
			)
			(layer "B.SilkS")
		)
		(fp_line
			(start -1.2192 2.1082)
			(end 1.2192 2.1082)
			(stroke
				(width 0.1524)
				(type default)
			)
			(layer "B.SilkS")
		)
		(fp_line
			(start -1.2192 -2.1082)
			(end -1.2192 2.1082)
			(stroke
				(width 0.1524)
				(type default)
			)
			(layer "B.SilkS")
		)
		(pad "" np_thru_hole circle
			(at -3.4671 -1.27 90)
			(size 1.0414 1.0414)
			(drill 1.0414)
			(layers "*.Cu" "*.Mask")
			(clearance 0.381)
			(thermal_gap 0.381)
		)
		(pad "" np_thru_hole circle
			(at -3.4671 1.27 90)
			(size 1.0414 1.0414)
			(drill 1.0414)
			(layers "*.Cu" "*.Mask")
			(clearance 0.381)
			(thermal_gap 0.381)
		)
		(pad "" np_thru_hole circle
			(at 2.8829 -1.27 90)
			(size 1.0414 1.0414)
			(drill 1.0414)
			(layers "*.Cu" "*.Mask")
			(clearance 0.381)
			(thermal_gap 0.381)
		)
		(pad "" np_thru_hole circle
			(at 2.8829 1.27 90)
			(size 1.0414 1.0414)
			(drill 1.0414)
			(layers "*.Cu" "*.Mask")
			(clearance 0.381)
			(thermal_gap 0.381)
		)
		(pad "1" smd rect
			(at -0.8255 -0.249936 90)
			(size 0.3048 0.508)
			(layers "B.Cu" "B.Mask" "B.Paste")
			(net "DELTA_L_85_10INCH_IN6_DN")
		)
		(pad "2" smd rect
			(at -0.8255 0.249936 90)
			(size 0.3048 0.508)
			(layers "B.Cu" "B.Mask" "B.Paste")
			(net "DELTA_L_85_10INCH_IN6_DP")
		)
		(pad "3" smd circle
			(at 0 0)
			(size 0 0)
			(layers "B.Cu" "B.Mask" "B.Paste")
			(net "DELTA_L_GND_1")
		)
		(zone
			(layers "F.Cu" "B.Cu" "In1.Cu" "In2.Cu" "In3.Cu" "In4.Cu" "In5.Cu" "In6.Cu"
				"In7.Cu" "In8.Cu" "In9.Cu" "In10.Cu" "In11.Cu" "In12.Cu" "In13.Cu" "In14.Cu"
				"In15.Cu" "In16.Cu"
			)
			(hatch none 0.5)
			(connect_pads
				(clearance 0)
			)
			(min_thickness 0.25)
			(keepout
				(tracks not_allowed)
				(vias allowed)
				(pads allowed)
				(copperpour not_allowed)
				(footprints allowed)
			)
			(placement
				(enabled no)
				(sheetname "")
			)
			(fill
				(thermal_gap 0.5)
				(thermal_bridge_width 0.5)
				(island_removal_mode 0)
			)
			(polygon
				(pts
					(arc
						(start 258.775708 1.653794)
						(mid 256.921508 1.653794)
						(end 258.775708 1.653794)
					)
				)
			)
		)
		(zone
			(layers "F.Cu" "B.Cu" "In1.Cu" "In2.Cu" "In3.Cu" "In4.Cu" "In5.Cu" "In6.Cu"
				"In7.Cu" "In8.Cu" "In9.Cu" "In10.Cu" "In11.Cu" "In12.Cu" "In13.Cu" "In14.Cu"
				"In15.Cu" "In16.Cu"
			)
			(hatch none 0.5)
			(connect_pads
				(clearance 0)
			)
			(min_thickness 0.25)
			(keepout
				(tracks not_allowed)
				(vias allowed)
				(pads allowed)
				(copperpour not_allowed)
				(footprints allowed)
			)
			(placement
				(enabled no)
				(sheetname "")
			)
			(fill
				(thermal_gap 0.5)
				(thermal_bridge_width 0.5)
				(island_removal_mode 0)
			)
			(polygon
				(pts
					(arc
						(start 258.775708 4.193794)
						(mid 256.921508 4.193794)
						(end 258.775708 4.193794)
					)
				)
			)
		)
		(zone
			(layers "F.Cu" "B.Cu" "In1.Cu" "In2.Cu" "In3.Cu" "In4.Cu" "In5.Cu" "In6.Cu"
				"In7.Cu" "In8.Cu" "In9.Cu" "In10.Cu" "In11.Cu" "In12.Cu" "In13.Cu" "In14.Cu"
				"In15.Cu" "In16.Cu"
			)
			(hatch none 0.5)
			(connect_pads
				(clearance 0)
			)
			(min_thickness 0.25)
			(keepout
				(tracks not_allowed)
				(vias allowed)
				(pads allowed)
				(copperpour not_allowed)
				(footprints allowed)
			)
			(placement
				(enabled no)
				(sheetname "")
			)
			(fill
				(thermal_gap 0.5)
				(thermal_bridge_width 0.5)
				(island_removal_mode 0)
			)
			(polygon
				(pts
					(arc
						(start 265.125708 1.653794)
						(mid 263.271508 1.653794)
						(end 265.125708 1.653794)
					)
				)
			)
		)
		(zone
			(layers "F.Cu" "B.Cu" "In1.Cu" "In2.Cu" "In3.Cu" "In4.Cu" "In5.Cu" "In6.Cu"
				"In7.Cu" "In8.Cu" "In9.Cu" "In10.Cu" "In11.Cu" "In12.Cu" "In13.Cu" "In14.Cu"
				"In15.Cu" "In16.Cu"
			)
			(hatch none 0.5)
			(connect_pads
				(clearance 0)
			)
			(min_thickness 0.25)
			(keepout
				(tracks not_allowed)
				(vias allowed)
				(pads allowed)
				(copperpour not_allowed)
				(footprints allowed)
			)
			(placement
				(enabled no)
				(sheetname "")
			)
			(fill
				(thermal_gap 0.5)
				(thermal_bridge_width 0.5)
				(island_removal_mode 0)
			)
			(polygon
				(pts
					(arc
						(start 265.125708 4.193794)
						(mid 263.271508 4.193794)
						(end 265.125708 4.193794)
					)
				)
			)
		)
		(zone
			(layer "B.Cu")
			(hatch none 0.5)
			(connect_pads
				(clearance 0)
			)
			(min_thickness 0.25)
			(keepout
				(tracks not_allowed)
				(vias allowed)
				(pads allowed)
				(copperpour not_allowed)
				(footprints allowed)
			)
			(placement
				(enabled no)
				(sheetname "")
			)
			(fill
				(thermal_gap 0.5)
				(thermal_bridge_width 0.5)
				(island_removal_mode 0)
			)
			(polygon
				(pts
					(xy 261.849108 3.472434) (xy 261.849108 3.37693) (xy 261.252208 3.37693) (xy 261.252208 2.97053)
					(xy 261.849108 2.97053) (xy 261.849108 2.877058) (xy 261.252208 2.877058) (xy 261.252208 2.470658)
					(xy 261.849108 2.470658) (xy 261.849108 2.375154) (xy 261.150608 2.375154) (xy 261.150608 3.472434)
				)
			)
		)
	)
)
